# T6G (Grand Teton) — schematic netlist excerpt (pin names and nets, part order shuffled) for the footprints in the layout excerpt that follows; sources: Cadence DE-HDL packaged netlist, KiCad conversion of 04192023_DAF0TMB3IC0_F0TG_MB_C_brd_V02_OCP.brd

PC2198  Q_CAP  1UF 25V 10% X6S  pkg C0402  page 147 : A = P12V_AUX ; B = GND
R397  Q_RES  2.2K 5% CHIP  pkg 0402LF  page 27 : A = P3V3_AUX ; B = CPU0_SP5R1

(kicad_pcb
	(version 20260206)
	(generator "pcbnew")
	(generator_version "10.0")
	(general
		(thickness 1.6)
		(legacy_teardrops no)
	)
	(paper "A4")
	(title_block
		(title "04192023_DAF0TMB3IC0_F0TG_MB_C_brd_V02_OCP.brd")
		(comment 1 "Grand Teton / footprints 4718-4719 of 8354")
	)
	(layers
		(0 "F.Cu" signal "TOP")
		(4 "In1.Cu" signal "GND")
		(6 "In2.Cu" signal "IN1")
		(8 "In3.Cu" signal "GND1")
		(10 "In4.Cu" signal "IN2")
		(12 "In5.Cu" signal "GND2")
		(14 "In6.Cu" signal "IN3")
		(16 "In7.Cu" signal "GND3")
		(18 "In8.Cu" signal "VCC")
		(20 "In9.Cu" signal "VCC1")
		(22 "In10.Cu" signal "GND4")
		(24 "In11.Cu" signal "IN4")
		(26 "In12.Cu" signal "GND5")
		(28 "In13.Cu" signal "IN5")
		(30 "In14.Cu" signal "GND6")
		(32 "In15.Cu" signal "IN6")
		(34 "In16.Cu" signal "GND7")
		(2 "B.Cu" signal "BOTTOM")
		(9 "F.Adhes" user "F.Adhesive")
		(11 "B.Adhes" user "B.Adhesive")
		(13 "F.Paste" user "Package Geometry/Pastemask Top")
		(15 "B.Paste" user "Package Geometry/Pastemask Bottom")
		(5 "F.SilkS" user "Ref Des/Silkscreen Top")
		(7 "B.SilkS" user "Ref Des/Silkscreen Bottom")
		(1 "F.Mask" user "Board Geometry/Soldermask Top")
		(3 "B.Mask" user "Board Geometry/Soldermask Bottom")
		(17 "Dwgs.User" user "User.Drawings")
		(19 "Cmts.User" user "User.Comments")
		(21 "Eco1.User" user "User.Eco1")
		(23 "Eco2.User" user "User.Eco2")
		(25 "Edge.Cuts" user "Board Geometry/Outline")
		(27 "Margin" user)
		(31 "F.CrtYd" user "Package Geometry/Place Bound Top")
		(29 "B.CrtYd" user "Package Geometry/Place Bound Bottom")
		(35 "F.Fab" user "Ref Des/Assembly Top")
		(33 "B.Fab" user "Ref Des/Assembly Bottom")
	)
	(footprint ""
		(layer "F.Cu")
		(at 186.804046 -94.876112 -90)
		(property "Reference" "R397"
			(at 0 0 270)
			(layer "F.SilkS")
			(hide yes)
			(effects
				(font
					(size 1.27 1.27)
				)
			)
		)
		(property "Value" ""
			(at 0 0 270)
			(layer "F.Fab")
			(effects
				(font
					(size 1.27 1.27)
				)
			)
		)
		(duplicate_pad_numbers_are_jumpers no)
		(fp_line
			(start -0.7874 0.4064)
			(end -0.7874 -0.4064)
			(stroke
				(width 0.1524)
				(type default)
			)
			(layer "F.SilkS")
		)
		(fp_line
			(start 0.7874 0.4064)
			(end -0.7874 0.4064)
			(stroke
				(width 0.1524)
				(type default)
			)
			(layer "F.SilkS")
		)
		(fp_line
			(start -0.7874 -0.4064)
			(end 0.7874 -0.4064)
			(stroke
				(width 0.1524)
				(type default)
			)
			(layer "F.SilkS")
		)
		(fp_line
			(start 0.7874 -0.4064)
			(end 0.7874 0.4064)
			(stroke
				(width 0.1524)
				(type default)
			)
			(layer "F.SilkS")
		)
		(fp_line
			(start -0.67945 0.3048)
			(end -0.67945 -0.305054)
			(stroke
				(width 0.1)
				(type default)
			)
			(layer "F.Fab")
		)
		(fp_line
			(start -0.12065 0.3048)
			(end -0.67945 0.3048)
			(stroke
				(width 0.1)
				(type default)
			)
			(layer "F.Fab")
		)
		(fp_line
			(start 0.120396 0.3048)
			(end 0.120396 0.2794)
			(stroke
				(width 0.1)
				(type default)
			)
			(layer "F.Fab")
		)
		(fp_line
			(start 0.67945 0.3048)
			(end 0.120396 0.3048)
			(stroke
				(width 0.1)
				(type default)
			)
			(layer "F.Fab")
		)
		(fp_line
			(start -0.12065 0.2794)
			(end -0.12065 0.3048)
			(stroke
				(width 0.1)
				(type default)
			)
			(layer "F.Fab")
		)
		(fp_line
			(start 0.120396 0.2794)
			(end -0.12065 0.2794)
			(stroke
				(width 0.1)
				(type default)
			)
			(layer "F.Fab")
		)
		(fp_line
			(start -0.12065 -0.2794)
			(end 0.12065 -0.2794)
			(stroke
				(width 0.1)
				(type default)
			)
			(layer "F.Fab")
		)
		(fp_line
			(start 0.12065 -0.2794)
			(end 0.12065 -0.3048)
			(stroke
				(width 0.1)
				(type default)
			)
			(layer "F.Fab")
		)
		(fp_line
			(start 0.12065 -0.3048)
			(end 0.67945 -0.3048)
			(stroke
				(width 0.1)
				(type default)
			)
			(layer "F.Fab")
		)
		(fp_line
			(start 0.67945 -0.3048)
			(end 0.67945 0.3048)
			(stroke
				(width 0.1)
				(type default)
			)
			(layer "F.Fab")
		)
		(fp_line
			(start -0.67945 -0.305054)
			(end -0.12065 -0.305054)
			(stroke
				(width 0.1)
				(type default)
			)
			(layer "F.Fab")
		)
		(fp_line
			(start -0.12065 -0.305054)
			(end -0.12065 -0.2794)
			(stroke
				(width 0.1)
				(type default)
			)
			(layer "F.Fab")
		)
		(pad "1" smd circle
			(at -0.40005 0 270)
			(size 0 0)
			(layers "F.Cu" "F.Mask" "F.Paste")
			(net "P3V3_AUX")
		)
		(pad "2" smd circle
			(at 0.40005 0 270)
			(size 0 0)
			(layers "F.Cu" "F.Mask" "F.Paste")
			(net "CPU0_SP5R1")
		)
	)
	(footprint ""
		(layer "F.Cu")
		(at 259.89788 -47.650146 90)
		(property "Reference" "PC2198"
			(at 0 0 90)
			(layer "F.SilkS")
			(hide yes)
			(effects
				(font
					(size 1.27 1.27)
				)
			)
		)
		(property "Value" ""
			(at 0 0 90)
			(layer "F.Fab")
			(effects
				(font
					(size 1.27 1.27)
				)
			)
		)
		(duplicate_pad_numbers_are_jumpers no)
		(fp_line
			(start 0.7874 -0.4064)
			(end 0.7874 0.4064)
			(stroke
				(width 0.1524)
				(type default)
			)
			(layer "F.SilkS")
		)
		(fp_line
			(start -0.7874 -0.4064)
			(end 0.7874 -0.4064)
			(stroke
				(width 0.1524)
				(type default)
			)
			(layer "F.SilkS")
		)
		(fp_line
			(start 0.7874 0.4064)
			(end -0.7874 0.4064)
			(stroke
				(width 0.1524)
				(type default)
			)
			(layer "F.SilkS")
		)
		(fp_line
			(start -0.7874 0.4064)
			(end -0.7874 -0.4064)
			(stroke
				(width 0.1524)
				(type default)
			)
			(layer "F.SilkS")
		)
		(fp_line
			(start -0.12065 -0.305054)
			(end -0.12065 -0.2794)
			(stroke
				(width 0.1)
				(type default)
			)
			(layer "F.Fab")
		)
		(fp_line
			(start -0.67945 -0.305054)
			(end -0.12065 -0.305054)
			(stroke
				(width 0.1)
				(type default)
			)
			(layer "F.Fab")
		)
		(fp_line
			(start 0.67945 -0.3048)
			(end 0.67945 0.3048)
			(stroke
				(width 0.1)
				(type default)
			)
			(layer "F.Fab")
		)
		(fp_line
			(start 0.12065 -0.3048)
			(end 0.67945 -0.3048)
			(stroke
				(width 0.1)
				(type default)
			)
			(layer "F.Fab")
		)
		(fp_line
			(start 0.12065 -0.2794)
			(end 0.12065 -0.3048)
			(stroke
				(width 0.1)
				(type default)
			)
			(layer "F.Fab")
		)
		(fp_line
			(start -0.12065 -0.2794)
			(end 0.12065 -0.2794)
			(stroke
				(width 0.1)
				(type default)
			)
			(layer "F.Fab")
		)
		(fp_line
			(start 0.120396 0.2794)
			(end -0.12065 0.2794)
			(stroke
				(width 0.1)
				(type default)
			)
			(layer "F.Fab")
		)
		(fp_line
			(start -0.12065 0.2794)
			(end -0.12065 0.3048)
			(stroke
				(width 0.1)
				(type default)
			)
			(layer "F.Fab")
		)
		(fp_line
			(start 0.67945 0.3048)
			(end 0.120396 0.3048)
			(stroke
				(width 0.1)
				(type default)
			)
			(layer "F.Fab")
		)
		(fp_line
			(start 0.120396 0.3048)
			(end 0.120396 0.2794)
			(stroke
				(width 0.1)
				(type default)
			)
			(layer "F.Fab")
		)
		(fp_line
			(start -0.12065 0.3048)
			(end -0.67945 0.3048)
			(stroke
				(width 0.1)
				(type default)
			)
			(layer "F.Fab")
		)
		(fp_line
			(start -0.67945 0.3048)
			(end -0.67945 -0.305054)
			(stroke
				(width 0.1)
				(type default)
			)
			(layer "F.Fab")
		)
		(pad "1" smd circle
			(at -0.40005 0 90)
			(size 0 0)
			(layers "F.Cu" "F.Mask" "F.Paste")
			(net "P12V_AUX")
		)
		(pad "2" smd circle
			(at 0.40005 0 90)
			(size 0 0)
			(layers "F.Cu" "F.Mask" "F.Paste")
			(net "GND")
		)
	)
)
